(kicad_pcb
	(version 20260206)
	(generator "pcbnew")
	(generator_version "10.0")
	(general
		(thickness 1.6)
		(legacy_teardrops no)
	)
	(paper "A4")
	(title_block
		(title "04192023_DAF0TMB3IC0_F0TG_MB_C_brd_V02_OCP.brd")
		(comment 1 "Grand Teton / footprint 3846 of 8354 (J110), pads 1-48 of 48")
	)
	(layers
		(0 "F.Cu" signal "TOP")
		(4 "In1.Cu" signal "GND")
		(6 "In2.Cu" signal "IN1")
		(8 "In3.Cu" signal "GND1")
		(10 "In4.Cu" signal "IN2")
		(12 "In5.Cu" signal "GND2")
		(14 "In6.Cu" signal "IN3")
		(16 "In7.Cu" signal "GND3")
		(18 "In8.Cu" signal "VCC")
		(20 "In9.Cu" signal "VCC1")
		(22 "In10.Cu" signal "GND4")
		(24 "In11.Cu" signal "IN4")
		(26 "In12.Cu" signal "GND5")
		(28 "In13.Cu" signal "IN5")
		(30 "In14.Cu" signal "GND6")
		(32 "In15.Cu" signal "IN6")
		(34 "In16.Cu" signal "GND7")
		(2 "B.Cu" signal "BOTTOM")
		(9 "F.Adhes" user "F.Adhesive")
		(11 "B.Adhes" user "B.Adhesive")
		(13 "F.Paste" user "Package Geometry/Pastemask Top")
		(15 "B.Paste" user "Package Geometry/Pastemask Bottom")
		(5 "F.SilkS" user "Ref Des/Silkscreen Top")
		(7 "B.SilkS" user "Ref Des/Silkscreen Bottom")
		(1 "F.Mask" user "Board Geometry/Soldermask Top")
		(3 "B.Mask" user "Board Geometry/Soldermask Bottom")
		(17 "Dwgs.User" user "User.Drawings")
		(19 "Cmts.User" user "User.Comments")
		(21 "Eco1.User" user "User.Eco1")
		(23 "Eco2.User" user "User.Eco2")
		(25 "Edge.Cuts" user "Board Geometry/Outline")
		(27 "Margin" user)
		(31 "F.CrtYd" user "Package Geometry/Place Bound Top")
		(29 "B.CrtYd" user "Package Geometry/Place Bound Bottom")
		(35 "F.Fab" user "Ref Des/Assembly Top")
		(33 "B.Fab" user "Ref Des/Assembly Bottom")
	)
	(footprint ""
		(layer "F.Cu")
		(at 125.749812 -440.489848)
		(property "Reference" "J110"
			(at -4.40944 23.347172 0)
			(unlocked yes)
			(layer "F.SilkS")
			(effects
				(font
					(size 0.7874 0.5842)
					(thickness 0.1524)
				)
				(justify left)
			)
		)
		(property "Value" ""
			(at 0 0 0)
			(layer "F.Fab")
			(effects
				(font
					(size 1.27 1.27)
				)
			)
		)
		(duplicate_pad_numbers_are_jumpers no)
		(pad "A1" thru_hole rect
			(at 0 0 180)
			(size 0.766318 0.766318)
			(drill 0.359918)
			(layers "*.Cu" "*.Mask")
			(remove_unused_layers no)
			(net "GPU_FPGA_EROT_RECOV_BUF_N")
			(clearance 0.0508)
			(thermal_gap 0.0508)
			(padstack
				(mode front_inner_back)
				(layer "Inner"
					(shape circle)
					(size 0.766318 0.766318)
					(clearance 0.0508)
				)
				(layer "B.Cu"
					(shape rect)
					(size 0.766318 0.766318)
					(clearance 0.0508)
				)
			)
		)
		(pad "A2" thru_hole circle
			(at 1.999996 0.199898 180)
			(size 0.906272 0.906272)
			(drill 0.499872)
			(layers "*.Cu" "*.Mask")
			(remove_unused_layers no)
			(net "GND")
			(clearance 0.0508)
			(thermal_gap 0.0508)
		)
		(pad "A3" thru_hole circle
			(at 3.999992 0 180)
			(size 0.766318 0.766318)
			(drill 0.359918)
			(layers "*.Cu" "*.Mask")
			(remove_unused_layers no)
			(net "GPU_HMC_PRSNT_N")
			(clearance 0.0508)
			(thermal_gap 0.0508)
		)
		(pad "A4" thru_hole circle
			(at 5.999988 0.199898 180)
			(size 0.906272 0.906272)
			(drill 0.499872)
			(layers "*.Cu" "*.Mask")
			(remove_unused_layers no)
			(net "GND")
			(clearance 0.0508)
			(thermal_gap 0.0508)
		)
		(pad "A5" thru_hole circle
			(at 7.999984 0 180)
			(size 0.766318 0.766318)
			(drill 0.359918)
			(layers "*.Cu" "*.Mask")
			(remove_unused_layers no)
			(net "GPU_BASE_HMC_READY")
			(clearance 0.0508)
			(thermal_gap 0.0508)
		)
		(pad "A6" thru_hole circle
			(at 9.99998 0.199898 180)
			(size 0.906272 0.906272)
			(drill 0.499872)
			(layers "*.Cu" "*.Mask")
			(remove_unused_layers no)
			(net "GND")
			(clearance 0.0508)
			(thermal_gap 0.0508)
		)
		(pad "A7" thru_hole circle
			(at 11.999976 0 180)
			(size 0.766318 0.766318)
			(drill 0.359918)
			(layers "*.Cu" "*.Mask")
			(remove_unused_layers no)
			(net "GPU_BASE_STBY_EN_BUF")
			(clearance 0.0508)
			(thermal_gap 0.0508)
		)
		(pad "A8" thru_hole circle
			(at 13.999972 0.199898 180)
			(size 0.906272 0.906272)
			(drill 0.499872)
			(layers "*.Cu" "*.Mask")
			(remove_unused_layers no)
			(net "GND")
			(clearance 0.0508)
			(thermal_gap 0.0508)
		)
		(pad "B1" thru_hole circle
			(at 0 1.199896 180)
			(size 0.906272 0.906272)
			(drill 0.499872)
			(layers "*.Cu" "*.Mask")
			(remove_unused_layers no)
			(net "GND")
			(clearance 0.0508)
			(thermal_gap 0.0508)
		)
		(pad "B3" thru_hole circle
			(at 3.999992 1.199896 180)
			(size 0.906272 0.906272)
			(drill 0.499872)
			(layers "*.Cu" "*.Mask")
			(remove_unused_layers no)
			(net "GND")
			(clearance 0.0508)
			(thermal_gap 0.0508)
		)
		(pad "B5" thru_hole circle
			(at 7.999984 1.199896 180)
			(size 0.906272 0.906272)
			(drill 0.499872)
			(layers "*.Cu" "*.Mask")
			(remove_unused_layers no)
			(net "GND")
			(clearance 0.0508)
			(thermal_gap 0.0508)
		)
		(pad "B7" thru_hole circle
			(at 11.999976 1.199896 180)
			(size 0.906272 0.906272)
			(drill 0.499872)
			(layers "*.Cu" "*.Mask")
			(remove_unused_layers no)
			(net "GND")
			(clearance 0.0508)
			(thermal_gap 0.0508)
		)
		(pad "D2" thru_hole circle
			(at 1.999996 3.800094 180)
			(size 0.906272 0.906272)
			(drill 0.499872)
			(layers "*.Cu" "*.Mask")
			(remove_unused_layers no)
			(net "GND")
			(clearance 0.0508)
			(thermal_gap 0.0508)
		)
		(pad "D4" thru_hole circle
			(at 5.999988 3.800094 180)
			(size 0.906272 0.906272)
			(drill 0.499872)
			(layers "*.Cu" "*.Mask")
			(remove_unused_layers no)
			(net "GND")
			(clearance 0.0508)
			(thermal_gap 0.0508)
		)
		(pad "D6" thru_hole circle
			(at 9.99998 3.800094 180)
			(size 0.906272 0.906272)
			(drill 0.499872)
			(layers "*.Cu" "*.Mask")
			(remove_unused_layers no)
			(net "GND")
			(clearance 0.0508)
			(thermal_gap 0.0508)
		)
		(pad "D8" thru_hole circle
			(at 13.999972 3.800094 180)
			(size 0.906272 0.906272)
			(drill 0.499872)
			(layers "*.Cu" "*.Mask")
			(remove_unused_layers no)
			(net "GND")
			(clearance 0.0508)
			(thermal_gap 0.0508)
		)
		(pad "E1" thru_hole circle
			(at 0 4.800092 180)
			(size 0.906272 0.906272)
			(drill 0.499872)
			(layers "*.Cu" "*.Mask")
			(remove_unused_layers no)
			(net "GND")
			(clearance 0.0508)
			(thermal_gap 0.0508)
		)
		(pad "E3" thru_hole circle
			(at 3.999992 4.800092 180)
			(size 0.906272 0.906272)
			(drill 0.499872)
			(layers "*.Cu" "*.Mask")
			(remove_unused_layers no)
			(net "GND")
			(clearance 0.0508)
			(thermal_gap 0.0508)
		)
		(pad "E5" thru_hole circle
			(at 7.999984 4.800092 180)
			(size 0.906272 0.906272)
			(drill 0.499872)
			(layers "*.Cu" "*.Mask")
			(remove_unused_layers no)
			(net "GND")
			(clearance 0.0508)
			(thermal_gap 0.0508)
		)
		(pad "E7" thru_hole circle
			(at 11.999976 4.800092 180)
			(size 0.906272 0.906272)
			(drill 0.499872)
			(layers "*.Cu" "*.Mask")
			(remove_unused_layers no)
			(net "GND")
			(clearance 0.0508)
			(thermal_gap 0.0508)
		)
		(pad "G2" thru_hole circle
			(at 1.999996 7.400036 180)
			(size 0.906272 0.906272)
			(drill 0.499872)
			(layers "*.Cu" "*.Mask")
			(remove_unused_layers no)
			(net "GND")
			(clearance 0.0508)
			(thermal_gap 0.0508)
		)
		(pad "G4" thru_hole circle
			(at 5.999988 7.400036 180)
			(size 0.906272 0.906272)
			(drill 0.499872)
			(layers "*.Cu" "*.Mask")
			(remove_unused_layers no)
			(net "GND")
			(clearance 0.0508)
			(thermal_gap 0.0508)
		)
		(pad "G6" thru_hole circle
			(at 9.99998 7.400036 180)
			(size 0.906272 0.906272)
			(drill 0.499872)
			(layers "*.Cu" "*.Mask")
			(remove_unused_layers no)
			(net "GND")
			(clearance 0.0508)
			(thermal_gap 0.0508)
		)
		(pad "G8" thru_hole circle
			(at 13.999972 7.400036 180)
			(size 0.906272 0.906272)
			(drill 0.499872)
			(layers "*.Cu" "*.Mask")
			(remove_unused_layers no)
			(net "GND")
			(clearance 0.0508)
			(thermal_gap 0.0508)
		)
		(pad "H1" thru_hole circle
			(at 0 8.400034 180)
			(size 0.906272 0.906272)
			(drill 0.499872)
			(layers "*.Cu" "*.Mask")
			(remove_unused_layers no)
			(net "GND")
			(clearance 0.0508)
			(thermal_gap 0.0508)
		)
		(pad "H3" thru_hole circle
			(at 3.999992 8.400034 180)
			(size 0.906272 0.906272)
			(drill 0.499872)
			(layers "*.Cu" "*.Mask")
			(remove_unused_layers no)
			(net "GND")
			(clearance 0.0508)
			(thermal_gap 0.0508)
		)
		(pad "H5" thru_hole circle
			(at 7.999984 8.400034 180)
			(size 0.906272 0.906272)
			(drill 0.499872)
			(layers "*.Cu" "*.Mask")
			(remove_unused_layers no)
			(net "GND")
			(clearance 0.0508)
			(thermal_gap 0.0508)
		)
		(pad "H7" thru_hole circle
			(at 11.999976 8.400034 180)
			(size 0.906272 0.906272)
			(drill 0.499872)
			(layers "*.Cu" "*.Mask")
			(remove_unused_layers no)
			(net "GND")
			(clearance 0.0508)
			(thermal_gap 0.0508)
		)
		(pad "J2" thru_hole circle
			(at 1.999996 10.999978 180)
			(size 0.906272 0.906272)
			(drill 0.499872)
			(layers "*.Cu" "*.Mask")
			(remove_unused_layers no)
			(net "GND")
			(clearance 0.0508)
			(thermal_gap 0.0508)
		)
		(pad "J4" thru_hole circle
			(at 5.999988 10.999978 180)
			(size 0.906272 0.906272)
			(drill 0.499872)
			(layers "*.Cu" "*.Mask")
			(remove_unused_layers no)
			(net "GND")
			(clearance 0.0508)
			(thermal_gap 0.0508)
		)
		(pad "J6" thru_hole circle
			(at 9.99998 10.999978 180)
			(size 0.906272 0.906272)
			(drill 0.499872)
			(layers "*.Cu" "*.Mask")
			(remove_unused_layers no)
			(net "GND")
			(clearance 0.0508)
			(thermal_gap 0.0508)
		)
		(pad "J8" thru_hole circle
			(at 13.999972 10.999978 180)
			(size 0.906272 0.906272)
			(drill 0.499872)
			(layers "*.Cu" "*.Mask")
			(remove_unused_layers no)
			(net "GND")
			(clearance 0.0508)
			(thermal_gap 0.0508)
		)
		(pad "K1" thru_hole circle
			(at 0 11.999976 180)
			(size 0.906272 0.906272)
			(drill 0.499872)
			(layers "*.Cu" "*.Mask")
			(remove_unused_layers no)
			(net "GND")
			(clearance 0.0508)
			(thermal_gap 0.0508)
		)
		(pad "K3" thru_hole circle
			(at 3.999992 11.999976 180)
			(size 0.906272 0.906272)
			(drill 0.499872)
			(layers "*.Cu" "*.Mask")
			(remove_unused_layers no)
			(net "GND")
			(clearance 0.0508)
			(thermal_gap 0.0508)
		)
		(pad "K5" thru_hole circle
			(at 7.999984 11.999976 180)
			(size 0.906272 0.906272)
			(drill 0.499872)
			(layers "*.Cu" "*.Mask")
			(remove_unused_layers no)
			(net "GND")
			(clearance 0.0508)
			(thermal_gap 0.0508)
		)
		(pad "K7" thru_hole circle
			(at 11.999976 11.999976 180)
			(size 0.906272 0.906272)
			(drill 0.499872)
			(layers "*.Cu" "*.Mask")
			(remove_unused_layers no)
			(net "GND")
			(clearance 0.0508)
			(thermal_gap 0.0508)
		)
		(pad "M2" thru_hole circle
			(at 1.999996 14.59992 180)
			(size 0.906272 0.906272)
			(drill 0.499872)
			(layers "*.Cu" "*.Mask")
			(remove_unused_layers no)
			(net "GND")
			(clearance 0.0508)
			(thermal_gap 0.0508)
		)
		(pad "M4" thru_hole circle
			(at 5.999988 14.59992 180)
			(size 0.906272 0.906272)
			(drill 0.499872)
			(layers "*.Cu" "*.Mask")
			(remove_unused_layers no)
			(net "GND")
			(clearance 0.0508)
			(thermal_gap 0.0508)
		)
		(pad "M6" thru_hole circle
			(at 9.99998 14.59992 180)
			(size 0.906272 0.906272)
			(drill 0.499872)
			(layers "*.Cu" "*.Mask")
			(remove_unused_layers no)
			(net "GND")
			(clearance 0.0508)
			(thermal_gap 0.0508)
		)
		(pad "M8" thru_hole circle
			(at 13.999972 14.59992 180)
			(size 0.906272 0.906272)
			(drill 0.499872)
			(layers "*.Cu" "*.Mask")
			(remove_unused_layers no)
			(net "GND")
			(clearance 0.0508)
			(thermal_gap 0.0508)
		)
		(pad "N1" thru_hole circle
			(at 0 15.599918 180)
			(size 0.906272 0.906272)
			(drill 0.499872)
			(layers "*.Cu" "*.Mask")
			(remove_unused_layers no)
			(net "GND")
			(clearance 0.0508)
			(thermal_gap 0.0508)
		)
		(pad "N2" thru_hole circle
			(at 1.999996 15.80007 180)
			(size 0.766318 0.766318)
			(drill 0.359918)
			(layers "*.Cu" "*.Mask")
			(remove_unused_layers no)
			(net "GPU_FPGA_BOOT_EN_BUF")
			(clearance 0.0508)
			(thermal_gap 0.0508)
		)
		(pad "N3" thru_hole circle
			(at 3.999992 15.599918 180)
			(size 0.906272 0.906272)
			(drill 0.499872)
			(layers "*.Cu" "*.Mask")
			(remove_unused_layers no)
			(net "GND")
			(clearance 0.0508)
			(thermal_gap 0.0508)
		)
		(pad "N4" thru_hole circle
			(at 5.999988 15.80007 180)
			(size 0.766318 0.766318)
			(drill 0.359918)
			(layers "*.Cu" "*.Mask")
			(remove_unused_layers no)
			(net "FM_SMB_1_ALERT_GPU_N")
			(clearance 0.0508)
			(thermal_gap 0.0508)
		)
		(pad "N5" thru_hole circle
			(at 7.999984 15.599918 180)
			(size 0.906272 0.906272)
			(drill 0.499872)
			(layers "*.Cu" "*.Mask")
			(remove_unused_layers no)
			(net "GND")
			(clearance 0.0508)
			(thermal_gap 0.0508)
		)
		(pad "N6" thru_hole circle
			(at 9.99998 15.80007 180)
			(size 0.766318 0.766318)
			(drill 0.359918)
			(layers "*.Cu" "*.Mask")
			(remove_unused_layers no)
			(net "FM_SMB_2_ALERT_GPU_N")
			(clearance 0.0508)
			(thermal_gap 0.0508)
		)
		(pad "N7" thru_hole circle
			(at 11.999976 15.599918 180)
			(size 0.906272 0.906272)
			(drill 0.499872)
			(layers "*.Cu" "*.Mask")
			(remove_unused_layers no)
			(net "GND")
			(clearance 0.0508)
			(thermal_gap 0.0508)
		)
		(pad "N8" thru_hole circle
			(at 13.999972 15.80007 180)
			(size 0.766318 0.766318)
			(drill 0.359918)
			(layers "*.Cu" "*.Mask")
			(remove_unused_layers no)
			(net "GPU_FPGA_EROT_RST_BUF_N")
			(clearance 0.0508)
			(thermal_gap 0.0508)
		)
	)
)
